(kicad_pcb
	(version 20260206)
	(generator "pcbnew")
	(generator_version "10.0")
	(general
		(thickness 1.6)
		(legacy_teardrops no)
	)
	(paper "A4")
	(title_block
		(title "v1-tray-backplane — T6M_tray_BP_c_1023_1120.brd")
		(comment 1 "Open CloudServer (Microsoft) / footprint 71 of 170 (J17), pads 1-20 of 20")
	)
	(layers
		(0 "F.Cu" signal "TOP")
		(4 "In1.Cu" signal "GND")
		(6 "In2.Cu" signal "IN1")
		(8 "In3.Cu" signal "VCC")
		(10 "In4.Cu" signal "VCC1")
		(12 "In5.Cu" signal "IN2")
		(14 "In6.Cu" signal "GND1")
		(2 "B.Cu" signal "BOTTOM")
		(9 "F.Adhes" user "F.Adhesive")
		(11 "B.Adhes" user "B.Adhesive")
		(13 "F.Paste" user "Package Geometry/Pastemask Top")
		(15 "B.Paste" user "Package Geometry/Pastemask Bottom")
		(5 "F.SilkS" user "Ref Des/Silkscreen Top")
		(7 "B.SilkS" user "Ref Des/Silkscreen Bottom")
		(1 "F.Mask" user "Board Geometry/Soldermask Top")
		(3 "B.Mask" user "Board Geometry/Soldermask Bottom")
		(17 "Dwgs.User" user "User.Drawings")
		(19 "Cmts.User" user "User.Comments")
		(21 "Eco1.User" user "User.Eco1")
		(23 "Eco2.User" user "User.Eco2")
		(25 "Edge.Cuts" user "Board Geometry/Outline")
		(27 "Margin" user)
		(31 "F.CrtYd" user "Package Geometry/Place Bound Top")
		(29 "B.CrtYd" user "Package Geometry/Place Bound Bottom")
		(35 "F.Fab" user "Ref Des/Assembly Top")
		(33 "B.Fab" user "Ref Des/Assembly Bottom")
	)
	(footprint ""
		(layer "F.Cu")
		(at 370.614956 -49.795176)
		(property "Reference" "J17"
			(at 4.685538 2.36982 90)
			(unlocked yes)
			(layer "F.SilkS")
			(effects
				(font
					(size 0.7874 0.5842)
					(thickness 0.1524)
				)
				(justify left)
			)
		)
		(property "Value" ""
			(at 0 0 0)
			(layer "F.Fab")
			(effects
				(font
					(size 1.27 1.27)
				)
			)
		)
		(duplicate_pad_numbers_are_jumpers no)
		(pad "1" thru_hole circle
			(at 0 4.500118)
			(size 1.5494 1.5494)
			(drill 1.0414)
			(layers "*.Cu" "*.Mask")
			(remove_unused_layers no)
			(net "GND")
			(clearance 0)
		)
		(pad "2" thru_hole circle
			(at -8.58012 4.500118)
			(size 1.5494 1.5494)
			(drill 1.0414)
			(layers "*.Cu" "*.Mask")
			(remove_unused_layers no)
			(net "GND")
			(clearance 0)
		)
		(pad "3" thru_hole circle
			(at 0 14.500098)
			(size 1.5494 1.5494)
			(drill 1.0414)
			(layers "*.Cu" "*.Mask")
			(remove_unused_layers no)
			(net "GND")
			(clearance 0)
		)
		(pad "4" thru_hole circle
			(at -14.249908 9.500108)
			(size 1.5494 1.5494)
			(drill 1.0414)
			(layers "*.Cu" "*.Mask")
			(remove_unused_layers no)
			(net "GND")
			(clearance 0)
		)
		(pad "5" thru_hole circle
			(at -14.249908 19.500088)
			(size 1.5494 1.5494)
			(drill 1.0414)
			(layers "*.Cu" "*.Mask")
			(remove_unused_layers no)
			(net "GND")
			(clearance 0)
		)
		(pad "6" thru_hole circle
			(at 0 24.500078)
			(size 1.5494 1.5494)
			(drill 1.0414)
			(layers "*.Cu" "*.Mask")
			(remove_unused_layers no)
			(net "GND")
			(clearance 0)
		)
		(pad "7" thru_hole circle
			(at -5.679948 24.500078)
			(size 1.5494 1.5494)
			(drill 1.0414)
			(layers "*.Cu" "*.Mask")
			(remove_unused_layers no)
			(net "GND")
			(clearance 0)
		)
		(pad "8" thru_hole circle
			(at -11.079988 24.500078)
			(size 1.5494 1.5494)
			(drill 1.0414)
			(layers "*.Cu" "*.Mask")
			(remove_unused_layers no)
			(net "GND")
			(clearance 0)
		)
		(pad "9" thru_hole circle
			(at -14.249908 29.500068)
			(size 1.5494 1.5494)
			(drill 1.0414)
			(layers "*.Cu" "*.Mask")
			(remove_unused_layers no)
			(net "GND")
			(clearance 0)
		)
		(pad "10" thru_hole circle
			(at -14.249908 39.500048)
			(size 1.5494 1.5494)
			(drill 1.0414)
			(layers "*.Cu" "*.Mask")
			(remove_unused_layers no)
			(net "GND")
			(clearance 0)
		)
		(pad "11" thru_hole circle
			(at 0 27.29992)
			(size 1.3462 1.3462)
			(drill 0.9398)
			(layers "*.Cu" "*.Mask")
			(remove_unused_layers no)
			(net "GND")
			(clearance 0.0508)
			(thermal_gap 0.0508)
		)
		(pad "12" thru_hole circle
			(at 0 31.999936)
			(size 1.3462 1.3462)
			(drill 0.9398)
			(layers "*.Cu" "*.Mask")
			(remove_unused_layers no)
			(net "GND")
			(clearance 0.0508)
			(thermal_gap 0.0508)
		)
		(pad "13" thru_hole circle
			(at 0 36.999926)
			(size 1.3462 1.3462)
			(drill 0.9398)
			(layers "*.Cu" "*.Mask")
			(remove_unused_layers no)
			(net "GND")
			(clearance 0.0508)
			(thermal_gap 0.0508)
		)
		(pad "14" thru_hole circle
			(at -2.329942 41.60012)
			(size 1.3462 1.3462)
			(drill 0.9398)
			(layers "*.Cu" "*.Mask")
			(remove_unused_layers no)
			(net "GND")
			(clearance 0.0508)
			(thermal_gap 0.0508)
		)
		(pad "15" thru_hole circle
			(at -7.130034 41.60012)
			(size 1.3462 1.3462)
			(drill 0.9398)
			(layers "*.Cu" "*.Mask")
			(remove_unused_layers no)
			(net "GND")
			(clearance 0.0508)
			(thermal_gap 0.0508)
		)
		(pad "16" thru_hole circle
			(at -11.929872 41.60012)
			(size 1.3462 1.3462)
			(drill 0.9398)
			(layers "*.Cu" "*.Mask")
			(remove_unused_layers no)
			(net "GND")
			(clearance 0.0508)
			(thermal_gap 0.0508)
		)
		(pad "17" thru_hole circle
			(at -14.249908 27.29992)
			(size 1.3462 1.3462)
			(drill 0.9398)
			(layers "*.Cu" "*.Mask")
			(remove_unused_layers no)
			(net "GND")
			(clearance 0.0508)
			(thermal_gap 0.0508)
		)
		(pad "18" thru_hole circle
			(at -14.249908 31.999936)
			(size 1.3462 1.3462)
			(drill 0.9398)
			(layers "*.Cu" "*.Mask")
			(remove_unused_layers no)
			(net "GND")
			(clearance 0.0508)
			(thermal_gap 0.0508)
		)
		(pad "19" thru_hole circle
			(at -14.249908 36.999926)
			(size 1.3462 1.3462)
			(drill 0.9398)
			(layers "*.Cu" "*.Mask")
			(remove_unused_layers no)
			(net "GND")
			(clearance 0.0508)
			(thermal_gap 0.0508)
		)
		(pad "20" thru_hole circle
			(at 0 34.500058)
			(size 1.2446 1.2446)
			(drill 0.8382)
			(layers "*.Cu" "*.Mask")
			(remove_unused_layers no)
			(net "GND")
			(clearance 0.0508)
			(thermal_gap 0.0508)
		)
	)
)
